(kicad_pcb
	(version 20260206)
	(generator "pcbnew")
	(generator_version "10.0")
	(general
		(thickness 1.6)
		(legacy_teardrops no)
	)
	(paper "A4")
	(title_block
		(title "panther-plus-userver — 13130-1b_20150205.brd")
		(comment 1 "Honey Badger (Wiwynn) / footprints 17-25 of 1509")
	)
	(layers
		(0 "F.Cu" signal "TOP")
		(4 "In1.Cu" signal "L2")
		(6 "In2.Cu" signal "L3")
		(8 "In3.Cu" signal "L4")
		(10 "In4.Cu" signal "L5")
		(12 "In5.Cu" signal "L6")
		(14 "In6.Cu" signal "L7")
		(16 "In7.Cu" signal "L8")
		(18 "In8.Cu" signal "L9")
		(20 "In9.Cu" signal "L10")
		(22 "In10.Cu" signal "L11")
		(2 "B.Cu" signal "BOTTOM")
		(9 "F.Adhes" user "F.Adhesive")
		(11 "B.Adhes" user "B.Adhesive")
		(13 "F.Paste" user "Package Geometry/Pastemask Top")
		(15 "B.Paste" user "Package Geometry/Pastemask Bottom")
		(5 "F.SilkS" user "Ref Des/Silkscreen Top")
		(7 "B.SilkS" user "Ref Des/Silkscreen Bottom")
		(1 "F.Mask" user "Board Geometry/Soldermask Top")
		(3 "B.Mask" user "Board Geometry/Soldermask Bottom")
		(17 "Dwgs.User" user "User.Drawings")
		(19 "Cmts.User" user "User.Comments")
		(21 "Eco1.User" user "User.Eco1")
		(23 "Eco2.User" user "User.Eco2")
		(25 "Edge.Cuts" user "Board Geometry/Outline")
		(27 "Margin" user)
		(31 "F.CrtYd" user "Package Geometry/Place Bound Top")
		(29 "B.CrtYd" user "Package Geometry/Place Bound Bottom")
		(35 "F.Fab" user "Ref Des/Assembly Top")
		(33 "B.Fab" user "Ref Des/Assembly Bottom")
	)
	(footprint ""
		(layer "F.Cu")
		(at 155.702 -27.305)
		(property "Reference" "C235"
			(at 0 0 0)
			(layer "F.SilkS")
			(hide yes)
			(effects
				(font
					(size 1.27 1.27)
				)
			)
		)
		(property "Value" "SCD1U10V2KX-5GP"
			(at 1.1811 -2.7051 0)
			(unlocked yes)
			(layer "F.Fab")
			(hide yes)
			(effects
				(font
					(size 1.016 1.016)
					(thickness 0.1524)
				)
			)
		)
		(property "Device Type" "C402H22"
			(at 1.1811 -4.2291 0)
			(unlocked yes)
			(layer "F.Fab")
			(hide yes)
			(effects
				(font
					(size 1.016 1.016)
					(thickness 0.1524)
				)
			)
		)
		(duplicate_pad_numbers_are_jumpers no)
		(fp_rect
			(start -0.381 0.7366)
			(end 0.381 -0.7366)
			(stroke
				(width 0)
				(type default)
			)
			(fill no)
			(layer "F.CrtYd")
		)
		(fp_rect
			(start -0.381 0.7366)
			(end 0.381 -0.7366)
			(stroke
				(width 0)
				(type default)
			)
			(fill no)
			(layer "F.Fab")
		)
		(pad "1" smd custom
			(at 0 -0.4572)
			(size 0.1143 0.1143)
			(layers "F.Cu" "F.Mask" "F.Paste")
			(net "P3V3_STBY")
			(options
				(clearance outline)
				(anchor circle)
			)
			(primitives
				(gr_poly
					(pts
						(arc
							(start -0.254 -0.1778)
							(mid -0.239121 -0.213721)
							(end -0.2032 -0.2286)
						)
						(arc
							(start 0.2032 -0.2286)
							(mid 0.239121 -0.213721)
							(end 0.254 -0.1778)
						)
						(arc
							(start 0.254 0.1778)
							(mid 0.239121 0.213721)
							(end 0.2032 0.2286)
						)
						(arc
							(start -0.2032 0.2286)
							(mid -0.239121 0.213721)
							(end -0.254 0.1778)
						)
					)
					(width 0)
					(fill yes)
				)
			)
		)
		(pad "2" smd custom
			(at 0 0.4572)
			(size 0.1143 0.1143)
			(layers "F.Cu" "F.Mask" "F.Paste")
			(net "GND")
			(options
				(clearance outline)
				(anchor circle)
			)
			(primitives
				(gr_poly
					(pts
						(arc
							(start -0.254 -0.1778)
							(mid -0.239121 -0.213721)
							(end -0.2032 -0.2286)
						)
						(arc
							(start 0.2032 -0.2286)
							(mid 0.239121 -0.213721)
							(end 0.254 -0.1778)
						)
						(arc
							(start 0.254 0.1778)
							(mid 0.239121 0.213721)
							(end 0.2032 0.2286)
						)
						(arc
							(start -0.2032 0.2286)
							(mid -0.239121 0.213721)
							(end -0.254 0.1778)
						)
					)
					(width 0)
					(fill yes)
				)
			)
		)
	)
	(footprint ""
		(layer "F.Cu")
		(at 200.914 -31.242 -90)
		(property "Reference" "PC165"
			(at 0 0 270)
			(layer "F.SilkS")
			(hide yes)
			(effects
				(font
					(size 1.27 1.27)
				)
			)
		)
		(property "Value" "SC10U25V5KX-GP"
			(at 0 -4.9022 270)
			(unlocked yes)
			(layer "F.Fab")
			(hide yes)
			(effects
				(font
					(size 1.016 1.016)
					(thickness 0.1524)
				)
			)
		)
		(property "Device Type" "C805H56"
			(at 0 -6.8072 270)
			(unlocked yes)
			(layer "F.Fab")
			(hide yes)
			(effects
				(font
					(size 1.016 1.016)
					(thickness 0.1524)
				)
			)
		)
		(duplicate_pad_numbers_are_jumpers no)
		(fp_line
			(start 0.6096 0)
			(end -0.6096 0)
			(stroke
				(width 0.3048)
				(type default)
			)
			(layer "F.SilkS")
		)
		(fp_poly
			(pts
				(xy -0.9017 1.4351) (xy 0.9017 1.4351) (xy 0.9017 -1.4351) (xy -0.9017 -1.4351)
			)
			(stroke
				(width 0)
				(type default)
			)
			(fill no)
			(layer "F.CrtYd")
		)
		(fp_poly
			(pts
				(xy 0.9017 1.4351) (xy 0.9017 -1.4351) (xy -0.9017 -1.4351) (xy -0.9017 1.4351)
			)
			(stroke
				(width 0)
				(type default)
			)
			(fill no)
			(layer "F.Fab")
		)
		(pad "1" smd rect
			(at 0 -0.8382 270)
			(size 1.5494 0.9398)
			(layers "F.Cu" "F.Mask" "F.Paste")
			(net "PVDDR_VIN")
		)
		(pad "2" smd rect
			(at 0 0.8382 270)
			(size 1.5494 0.9398)
			(layers "F.Cu" "F.Mask" "F.Paste")
			(net "GND")
		)
	)
	(footprint ""
		(layer "F.Cu")
		(at 12.573 -60.071 180)
		(property "Reference" "PR52"
			(at 0 0 180)
			(layer "F.SilkS")
			(hide yes)
			(effects
				(font
					(size 1.27 1.27)
				)
			)
		)
		(property "Value" "56D2R2F-GP"
			(at 1.7907 -1.1176 180)
			(unlocked yes)
			(layer "F.Fab")
			(hide yes)
			(effects
				(font
					(size 1.016 1.016)
					(thickness 0.1524)
				)
			)
		)
		(property "Device Type" "R402H16"
			(at 1.7907 -2.6416 180)
			(unlocked yes)
			(layer "F.Fab")
			(hide yes)
			(effects
				(font
					(size 1.016 1.016)
					(thickness 0.1524)
				)
			)
		)
		(duplicate_pad_numbers_are_jumpers no)
		(fp_rect
			(start -0.381 0.8382)
			(end 0.381 -0.8382)
			(stroke
				(width 0)
				(type default)
			)
			(fill no)
			(layer "F.CrtYd")
		)
		(fp_rect
			(start -0.381 0.8382)
			(end 0.381 -0.8382)
			(stroke
				(width 0)
				(type default)
			)
			(fill no)
			(layer "F.Fab")
		)
		(pad "1" smd custom
			(at 0 -0.4318 180)
			(size 0.127 0.127)
			(layers "F.Cu" "F.Mask" "F.Paste")
			(net "P1V0")
			(options
				(clearance outline)
				(anchor circle)
			)
			(primitives
				(gr_poly
					(pts
						(arc
							(start -0.2032 -0.2794)
							(mid -0.239121 -0.264521)
							(end -0.254 -0.2286)
						)
						(arc
							(start -0.254 0.2286)
							(mid -0.239121 0.264521)
							(end -0.2032 0.2794)
						)
						(arc
							(start 0.2032 0.2794)
							(mid 0.239121 0.264521)
							(end 0.254 0.2286)
						)
						(arc
							(start 0.254 -0.2286)
							(mid 0.239121 -0.264521)
							(end 0.2032 -0.2794)
						)
					)
					(width 0)
					(fill yes)
				)
			)
		)
		(pad "2" smd custom
			(at 0 0.4318 180)
			(size 0.127 0.127)
			(layers "F.Cu" "F.Mask" "F.Paste")
			(net "SVID_CPU_CLK")
			(options
				(clearance outline)
				(anchor circle)
			)
			(primitives
				(gr_poly
					(pts
						(arc
							(start -0.2032 -0.2794)
							(mid -0.239121 -0.264521)
							(end -0.254 -0.2286)
						)
						(arc
							(start -0.254 0.2286)
							(mid -0.239121 0.264521)
							(end -0.2032 0.2794)
						)
						(arc
							(start 0.2032 0.2794)
							(mid 0.239121 0.264521)
							(end 0.254 0.2286)
						)
						(arc
							(start 0.254 -0.2286)
							(mid 0.239121 -0.264521)
							(end 0.2032 -0.2794)
						)
					)
					(width 0)
					(fill yes)
				)
			)
		)
	)
	(footprint ""
		(layer "F.Cu")
		(at 189.103 -48.514)
		(property "Reference" "C94"
			(at 0 0 0)
			(layer "F.SilkS")
			(hide yes)
			(effects
				(font
					(size 1.27 1.27)
				)
			)
		)
		(property "Value" "SCD1U16V2KX-3GP"
			(at 1.1811 -2.7051 0)
			(unlocked yes)
			(layer "F.Fab")
			(hide yes)
			(effects
				(font
					(size 1.016 1.016)
					(thickness 0.1524)
				)
			)
		)
		(property "Device Type" "C402H22"
			(at 1.1811 -4.2291 0)
			(unlocked yes)
			(layer "F.Fab")
			(hide yes)
			(effects
				(font
					(size 1.016 1.016)
					(thickness 0.1524)
				)
			)
		)
		(duplicate_pad_numbers_are_jumpers no)
		(fp_rect
			(start -0.381 0.7366)
			(end 0.381 -0.7366)
			(stroke
				(width 0)
				(type default)
			)
			(fill no)
			(layer "F.CrtYd")
		)
		(fp_rect
			(start -0.381 0.7366)
			(end 0.381 -0.7366)
			(stroke
				(width 0)
				(type default)
			)
			(fill no)
			(layer "F.Fab")
		)
		(pad "1" smd custom
			(at 0 -0.4572)
			(size 0.1143 0.1143)
			(layers "F.Cu" "F.Mask" "F.Paste")
			(net "P3V3_STBY")
			(options
				(clearance outline)
				(anchor circle)
			)
			(primitives
				(gr_poly
					(pts
						(arc
							(start -0.254 -0.1778)
							(mid -0.239121 -0.213721)
							(end -0.2032 -0.2286)
						)
						(arc
							(start 0.2032 -0.2286)
							(mid 0.239121 -0.213721)
							(end 0.254 -0.1778)
						)
						(arc
							(start 0.254 0.1778)
							(mid 0.239121 0.213721)
							(end 0.2032 0.2286)
						)
						(arc
							(start -0.2032 0.2286)
							(mid -0.239121 0.213721)
							(end -0.254 0.1778)
						)
					)
					(width 0)
					(fill yes)
				)
			)
		)
		(pad "2" smd custom
			(at 0 0.4572)
			(size 0.1143 0.1143)
			(layers "F.Cu" "F.Mask" "F.Paste")
			(net "GND")
			(options
				(clearance outline)
				(anchor circle)
			)
			(primitives
				(gr_poly
					(pts
						(arc
							(start -0.254 -0.1778)
							(mid -0.239121 -0.213721)
							(end -0.2032 -0.2286)
						)
						(arc
							(start 0.2032 -0.2286)
							(mid 0.239121 -0.213721)
							(end 0.254 -0.1778)
						)
						(arc
							(start 0.254 0.1778)
							(mid 0.239121 0.213721)
							(end 0.2032 0.2286)
						)
						(arc
							(start -0.2032 0.2286)
							(mid -0.239121 0.213721)
							(end -0.254 0.1778)
						)
					)
					(width 0)
					(fill yes)
				)
			)
		)
	)
	(footprint ""
		(layer "F.Cu")
		(at 69.596 -57.6072)
		(property "Reference" "C77"
			(at 0 0 0)
			(layer "F.SilkS")
			(hide yes)
			(effects
				(font
					(size 1.27 1.27)
				)
			)
		)
		(property "Value" "SCD1U16V2KX-3GP"
			(at 1.8923 -1.2065 0)
			(unlocked yes)
			(layer "F.Fab")
			(hide yes)
			(effects
				(font
					(size 1.016 1.016)
					(thickness 0.1524)
				)
			)
		)
		(property "Device Type" "C402H22"
			(at 1.8923 -2.7305 0)
			(unlocked yes)
			(layer "F.Fab")
			(hide yes)
			(effects
				(font
					(size 1.016 1.016)
					(thickness 0.1524)
				)
			)
		)
		(duplicate_pad_numbers_are_jumpers no)
		(fp_rect
			(start -0.381 0.7366)
			(end 0.381 -0.7366)
			(stroke
				(width 0)
				(type default)
			)
			(fill no)
			(layer "F.CrtYd")
		)
		(fp_rect
			(start -0.381 0.7366)
			(end 0.381 -0.7366)
			(stroke
				(width 0)
				(type default)
			)
			(fill no)
			(layer "F.Fab")
		)
		(pad "1" smd custom
			(at 0 -0.4572)
			(size 0.1143 0.1143)
			(layers "F.Cu" "F.Mask" "F.Paste")
			(net "P3V3_SENSE")
			(options
				(clearance outline)
				(anchor circle)
			)
			(primitives
				(gr_poly
					(pts
						(arc
							(start -0.254 -0.1778)
							(mid -0.239121 -0.213721)
							(end -0.2032 -0.2286)
						)
						(arc
							(start 0.2032 -0.2286)
							(mid 0.239121 -0.213721)
							(end 0.254 -0.1778)
						)
						(arc
							(start 0.254 0.1778)
							(mid 0.239121 0.213721)
							(end 0.2032 0.2286)
						)
						(arc
							(start -0.2032 0.2286)
							(mid -0.239121 0.213721)
							(end -0.254 0.1778)
						)
					)
					(width 0)
					(fill yes)
				)
			)
		)
		(pad "2" smd custom
			(at 0 0.4572)
			(size 0.1143 0.1143)
			(layers "F.Cu" "F.Mask" "F.Paste")
			(net "GND")
			(options
				(clearance outline)
				(anchor circle)
			)
			(primitives
				(gr_poly
					(pts
						(arc
							(start -0.254 -0.1778)
							(mid -0.239121 -0.213721)
							(end -0.2032 -0.2286)
						)
						(arc
							(start 0.2032 -0.2286)
							(mid 0.239121 -0.213721)
							(end 0.254 -0.1778)
						)
						(arc
							(start 0.254 0.1778)
							(mid 0.239121 0.213721)
							(end 0.2032 0.2286)
						)
						(arc
							(start -0.2032 0.2286)
							(mid -0.239121 0.213721)
							(end -0.254 0.1778)
						)
					)
					(width 0)
					(fill yes)
				)
			)
		)
	)
	(footprint ""
		(layer "F.Cu")
		(at 11.049 -61.468 -90)
		(property "Reference" "TP4"
			(at 0 0 270)
			(layer "F.SilkS")
			(hide yes)
			(effects
				(font
					(size 1.27 1.27)
				)
			)
		)
		(property "Value" "TPAD28-1-GP-U"
			(at 0.0508 -1.9304 270)
			(unlocked yes)
			(layer "F.Fab")
			(hide yes)
			(effects
				(font
					(size 1.016 1.016)
					(thickness 0.1524)
				)
			)
		)
		(property "Device Type" "TPAD28-1-U"
			(at 0.0508 -3.4544 270)
			(unlocked yes)
			(layer "F.Fab")
			(hide yes)
			(effects
				(font
					(size 1.016 1.016)
					(thickness 0.1524)
				)
			)
		)
		(duplicate_pad_numbers_are_jumpers no)
		(fp_poly
			(pts
				(arc
					(start 0 -0.3556)
					(mid 0 0.3556)
					(end 0 -0.3556)
				)
			)
			(stroke
				(width 0)
				(type default)
			)
			(fill no)
			(layer "F.CrtYd")
		)
		(fp_poly
			(pts
				(arc
					(start 0 -0.9525)
					(mid 0 0.9525)
					(end 0 -0.9525)
				)
			)
			(stroke
				(width 0)
				(type default)
			)
			(fill no)
			(layer "F.Fab")
		)
		(pad "1" smd circle
			(at 0 0 270)
			(size 0.7112 0.7112)
			(layers "F.Cu" "F.Mask" "F.Paste")
			(net "TP_PVCCP_VDIO")
		)
	)
	(footprint ""
		(layer "F.Cu")
		(at 74.4982 -39.624)
		(property "Reference" "C33"
			(at 0 0 0)
			(layer "F.SilkS")
			(hide yes)
			(effects
				(font
					(size 1.27 1.27)
				)
			)
		)
		(property "Value" "SC6P50V2CN-1GP"
			(at 1.1811 -2.7051 0)
			(unlocked yes)
			(layer "F.Fab")
			(hide yes)
			(effects
				(font
					(size 1.016 1.016)
					(thickness 0.1524)
				)
			)
		)
		(property "Device Type" "C402H22"
			(at 1.1811 -4.2291 0)
			(unlocked yes)
			(layer "F.Fab")
			(hide yes)
			(effects
				(font
					(size 1.016 1.016)
					(thickness 0.1524)
				)
			)
		)
		(duplicate_pad_numbers_are_jumpers no)
		(fp_rect
			(start -0.381 0.7366)
			(end 0.381 -0.7366)
			(stroke
				(width 0)
				(type default)
			)
			(fill no)
			(layer "F.CrtYd")
		)
		(fp_rect
			(start -0.381 0.7366)
			(end 0.381 -0.7366)
			(stroke
				(width 0)
				(type default)
			)
			(fill no)
			(layer "F.Fab")
		)
		(pad "1" smd custom
			(at 0 -0.4572)
			(size 0.1143 0.1143)
			(layers "F.Cu" "F.Mask" "F.Paste")
			(net "RTC_X2PAD")
			(options
				(clearance outline)
				(anchor circle)
			)
			(primitives
				(gr_poly
					(pts
						(arc
							(start -0.254 -0.1778)
							(mid -0.239121 -0.213721)
							(end -0.2032 -0.2286)
						)
						(arc
							(start 0.2032 -0.2286)
							(mid 0.239121 -0.213721)
							(end 0.254 -0.1778)
						)
						(arc
							(start 0.254 0.1778)
							(mid 0.239121 0.213721)
							(end 0.2032 0.2286)
						)
						(arc
							(start -0.2032 0.2286)
							(mid -0.239121 0.213721)
							(end -0.254 0.1778)
						)
					)
					(width 0)
					(fill yes)
				)
			)
		)
		(pad "2" smd custom
			(at 0 0.4572)
			(size 0.1143 0.1143)
			(layers "F.Cu" "F.Mask" "F.Paste")
			(net "GND")
			(options
				(clearance outline)
				(anchor circle)
			)
			(primitives
				(gr_poly
					(pts
						(arc
							(start -0.254 -0.1778)
							(mid -0.239121 -0.213721)
							(end -0.2032 -0.2286)
						)
						(arc
							(start 0.2032 -0.2286)
							(mid 0.239121 -0.213721)
							(end 0.254 -0.1778)
						)
						(arc
							(start 0.254 0.1778)
							(mid 0.239121 0.213721)
							(end 0.2032 0.2286)
						)
						(arc
							(start -0.2032 0.2286)
							(mid -0.239121 0.213721)
							(end -0.254 0.1778)
						)
					)
					(width 0)
					(fill yes)
				)
			)
		)
	)
	(footprint ""
		(layer "F.Cu")
		(at 6.3246 -50.546 180)
		(property "Reference" "R6"
			(at 0 0 180)
			(layer "F.SilkS")
			(hide yes)
			(effects
				(font
					(size 1.27 1.27)
				)
			)
		)
		(property "Value" "4K7R2F-GP"
			(at 0.064008 -3.993896 180)
			(unlocked yes)
			(layer "F.Fab")
			(hide yes)
			(effects
				(font
					(size 1.016 1.016)
					(thickness 0.1524)
				)
			)
		)
		(property "Device Type" "R402H16"
			(at 0.064008 -5.517896 180)
			(unlocked yes)
			(layer "F.Fab")
			(hide yes)
			(effects
				(font
					(size 1.016 1.016)
					(thickness 0.1524)
				)
			)
		)
		(duplicate_pad_numbers_are_jumpers no)
		(fp_rect
			(start -0.381 0.8382)
			(end 0.381 -0.8382)
			(stroke
				(width 0)
				(type default)
			)
			(fill no)
			(layer "F.CrtYd")
		)
		(fp_rect
			(start -0.381 0.8382)
			(end 0.381 -0.8382)
			(stroke
				(width 0)
				(type default)
			)
			(fill no)
			(layer "F.Fab")
		)
		(pad "1" smd custom
			(at 0 -0.4318 180)
			(size 0.127 0.127)
			(layers "F.Cu" "F.Mask" "F.Paste")
			(net "TEMP_1_A0")
			(options
				(clearance outline)
				(anchor circle)
			)
			(primitives
				(gr_poly
					(pts
						(arc
							(start -0.2032 -0.2794)
							(mid -0.239121 -0.264521)
							(end -0.254 -0.2286)
						)
						(arc
							(start -0.254 0.2286)
							(mid -0.239121 0.264521)
							(end -0.2032 0.2794)
						)
						(arc
							(start 0.2032 0.2794)
							(mid 0.239121 0.264521)
							(end 0.254 0.2286)
						)
						(arc
							(start 0.254 -0.2286)
							(mid 0.239121 -0.264521)
							(end 0.2032 -0.2794)
						)
					)
					(width 0)
					(fill yes)
				)
			)
		)
		(pad "2" smd custom
			(at 0 0.4318 180)
			(size 0.127 0.127)
			(layers "F.Cu" "F.Mask" "F.Paste")
			(net "GND")
			(options
				(clearance outline)
				(anchor circle)
			)
			(primitives
				(gr_poly
					(pts
						(arc
							(start -0.2032 -0.2794)
							(mid -0.239121 -0.264521)
							(end -0.254 -0.2286)
						)
						(arc
							(start -0.254 0.2286)
							(mid -0.239121 0.264521)
							(end -0.2032 0.2794)
						)
						(arc
							(start 0.2032 0.2794)
							(mid 0.239121 0.264521)
							(end 0.254 0.2286)
						)
						(arc
							(start 0.254 -0.2286)
							(mid 0.239121 -0.264521)
							(end 0.2032 -0.2794)
						)
					)
					(width 0)
					(fill yes)
				)
			)
		)
	)
	(footprint ""
		(layer "F.Cu")
		(at 156.718 -12.955778 180)
		(property "Reference" "C371"
			(at 0 0 180)
			(layer "F.SilkS")
			(hide yes)
			(effects
				(font
					(size 1.27 1.27)
				)
			)
		)
		(property "Value" "SC47U6D3V5MX-1-GP"
			(at 0 -4.9022 180)
			(unlocked yes)
			(layer "F.Fab")
			(hide yes)
			(effects
				(font
					(size 1.016 1.016)
					(thickness 0.1524)
				)
			)
		)
		(property "Device Type" "C805H54"
			(at 0 -6.8072 180)
			(unlocked yes)
			(layer "F.Fab")
			(hide yes)
			(effects
				(font
					(size 1.016 1.016)
					(thickness 0.1524)
				)
			)
		)
		(duplicate_pad_numbers_are_jumpers no)
		(fp_line
			(start 0.6096 0)
			(end -0.6096 0)
			(stroke
				(width 0.3048)
				(type default)
			)
			(layer "F.SilkS")
		)
		(fp_poly
			(pts
				(xy -0.9017 1.4351) (xy 0.9017 1.4351) (xy 0.9017 -1.4351) (xy -0.9017 -1.4351)
			)
			(stroke
				(width 0)
				(type default)
			)
			(fill no)
			(layer "F.CrtYd")
		)
		(fp_poly
			(pts
				(xy 0.9017 1.4351) (xy 0.9017 -1.4351) (xy -0.9017 -1.4351) (xy -0.9017 1.4351)
			)
			(stroke
				(width 0)
				(type default)
			)
			(fill no)
			(layer "F.Fab")
		)
		(pad "1" smd rect
			(at 0 -0.8382 180)
			(size 1.5494 0.9398)
			(layers "F.Cu" "F.Mask" "F.Paste")
			(net "PV_VDDR")
		)
		(pad "2" smd rect
			(at 0 0.8382 180)
			(size 1.5494 0.9398)
			(layers "F.Cu" "F.Mask" "F.Paste")
			(net "GND")
		)
	)
)
